# S9S_MB_2U (Grand Teton) — schematic netlist excerpt (pin names and nets, part order shuffled) for the footprints in the layout excerpt that follows; sources: Cadence DE-HDL packaged netlist, KiCad conversion of 03242023_DA0F0TMBIJ0_F0T_Motherboard_J_brd_V01_OCP.brd

R1747  Q_RES  0 5% CHIP  pkg 0805LF  page 257 : A = P1V8_PCH_AUX ; B = PGPPA_AUX

Q140  BC847BPN  IC  pkg SOT363XB  page 123
  E1  = GND
  B1  = H_CPU1_MEMTRIP_R
  C2  = H_CPU1_MEMTRIP
  E2  = PVNN_TERM_CPU1
  B2  = H_CPU1_MEMTRIP_OUT_VT_R_N
  C1  = H_CPU1_MEMTRIP_VT_N

(kicad_pcb
	(version 20260206)
	(generator "pcbnew")
	(generator_version "10.0")
	(general
		(thickness 1.6)
		(legacy_teardrops no)
	)
	(paper "A4")
	(title_block
		(title "03242023_DA0F0TMBIJ0_F0T_Motherboard_J_brd_V01_OCP.brd")
		(comment 1 "Grand Teton / footprints 2343-2344 of 6105")
	)
	(layers
		(0 "F.Cu" signal "TOP")
		(4 "In1.Cu" signal "GND")
		(6 "In2.Cu" signal "IN1")
		(8 "In3.Cu" signal "GND1")
		(10 "In4.Cu" signal "IN2")
		(12 "In5.Cu" signal "GND2")
		(14 "In6.Cu" signal "IN3")
		(16 "In7.Cu" signal "GND3")
		(18 "In8.Cu" signal "VCC")
		(20 "In9.Cu" signal "VCC1")
		(22 "In10.Cu" signal "GND4")
		(24 "In11.Cu" signal "IN4")
		(26 "In12.Cu" signal "GND5")
		(28 "In13.Cu" signal "IN5")
		(30 "In14.Cu" signal "GND6")
		(32 "In15.Cu" signal "IN6")
		(34 "In16.Cu" signal "GND7")
		(2 "B.Cu" signal "BOTTOM")
		(9 "F.Adhes" user "F.Adhesive")
		(11 "B.Adhes" user "B.Adhesive")
		(13 "F.Paste" user "Package Geometry/Pastemask Top")
		(15 "B.Paste" user "Package Geometry/Pastemask Bottom")
		(5 "F.SilkS" user "Ref Des/Silkscreen Top")
		(7 "B.SilkS" user "Ref Des/Silkscreen Bottom")
		(1 "F.Mask" user "Board Geometry/Soldermask Top")
		(3 "B.Mask" user "Board Geometry/Soldermask Bottom")
		(17 "Dwgs.User" user "User.Drawings")
		(19 "Cmts.User" user "User.Comments")
		(21 "Eco1.User" user "User.Eco1")
		(23 "Eco2.User" user "User.Eco2")
		(25 "Edge.Cuts" user "Board Geometry/Outline")
		(27 "Margin" user)
		(31 "F.CrtYd" user "Package Geometry/Place Bound Top")
		(29 "B.CrtYd" user "Package Geometry/Place Bound Bottom")
		(35 "F.Fab" user "Ref Des/Assembly Top")
		(33 "B.Fab" user "Ref Des/Assembly Bottom")
	)
	(footprint ""
		(layer "F.Cu")
		(at 133.65988 -103.723948 -90)
		(property "Reference" "Q140"
			(at -0.035052 -2.76479 90)
			(unlocked yes)
			(layer "F.SilkS")
			(effects
				(font
					(size 0.7874 0.5842)
					(thickness 0.1524)
				)
			)
		)
		(property "Value" ""
			(at 0 0 270)
			(layer "F.Fab")
			(effects
				(font
					(size 1.27 1.27)
				)
			)
		)
		(duplicate_pad_numbers_are_jumpers no)
		(fp_line
			(start -1.376172 1.199896)
			(end -1.376172 -1.199896)
			(stroke
				(width 0.1524)
				(type default)
			)
			(layer "F.SilkS")
		)
		(fp_line
			(start 1.376172 1.199896)
			(end -1.376172 1.199896)
			(stroke
				(width 0.1524)
				(type default)
			)
			(layer "F.SilkS")
		)
		(fp_line
			(start 0 -0.762)
			(end 0.508 -1.199896)
			(stroke
				(width 0.1524)
				(type default)
			)
			(layer "F.SilkS")
		)
		(fp_line
			(start -1.376172 -1.199896)
			(end -0.508 -1.199896)
			(stroke
				(width 0.1524)
				(type default)
			)
			(layer "F.SilkS")
		)
		(fp_line
			(start -0.508 -1.199896)
			(end 0 -0.762)
			(stroke
				(width 0.1524)
				(type default)
			)
			(layer "F.SilkS")
		)
		(fp_line
			(start 0.508 -1.199896)
			(end 1.376172 -1.199896)
			(stroke
				(width 0.1524)
				(type default)
			)
			(layer "F.SilkS")
		)
		(fp_line
			(start 1.376172 -1.199896)
			(end 1.376172 1.199896)
			(stroke
				(width 0.1524)
				(type default)
			)
			(layer "F.SilkS")
		)
		(fp_poly
			(pts
				(xy -0.880872 -1.369568) (xy -0.499872 -2.131568) (xy -1.261872 -2.131568)
			)
			(stroke
				(width 0)
				(type default)
			)
			(fill yes)
			(layer "F.SilkS")
		)
		(fp_line
			(start -0.674878 1.100074)
			(end -0.674878 -1.100074)
			(stroke
				(width 0.1)
				(type default)
			)
			(layer "F.Fab")
		)
		(fp_line
			(start 0.674878 1.100074)
			(end -0.674878 1.100074)
			(stroke
				(width 0.1)
				(type default)
			)
			(layer "F.Fab")
		)
		(fp_line
			(start -0.674878 -1.100074)
			(end 0.674878 -1.100074)
			(stroke
				(width 0.1)
				(type default)
			)
			(layer "F.Fab")
		)
		(fp_line
			(start 0.674878 -1.100074)
			(end 0.674878 1.100074)
			(stroke
				(width 0.1)
				(type default)
			)
			(layer "F.Fab")
		)
		(fp_poly
			(pts
				(xy -1.4605 -0.7493) (xy -2.2225 -1.1303) (xy -2.2225 -0.3683)
			)
			(stroke
				(width 0)
				(type default)
			)
			(fill yes)
			(layer "F.Fab")
		)
		(pad "1" smd rect
			(at -0.899922 -0.750062 180)
			(size 0.6096 0.6096)
			(layers "F.Cu" "F.Mask" "F.Paste")
			(net "GND")
		)
		(pad "2" smd rect
			(at -0.899922 0 180)
			(size 0.4064 0.6096)
			(layers "F.Cu" "F.Mask" "F.Paste")
			(net "H_CPU1_MEMTRIP_R")
		)
		(pad "3" smd rect
			(at -0.899922 0.750062 180)
			(size 0.6096 0.6096)
			(layers "F.Cu" "F.Mask" "F.Paste")
			(net "H_CPU1_MEMTRIP")
		)
		(pad "4" smd rect
			(at 0.899922 0.750062 180)
			(size 0.6096 0.6096)
			(layers "F.Cu" "F.Mask" "F.Paste")
			(net "PVNN_TERM_CPU1")
		)
		(pad "5" smd rect
			(at 0.899922 0 180)
			(size 0.4064 0.6096)
			(layers "F.Cu" "F.Mask" "F.Paste")
			(net "H_CPU1_MEMTRIP_OUT_VT_R_N")
		)
		(pad "6" smd rect
			(at 0.899922 -0.750062 180)
			(size 0.6096 0.6096)
			(layers "F.Cu" "F.Mask" "F.Paste")
			(net "H_CPU1_MEMTRIP_VT_N")
		)
	)
	(footprint ""
		(layer "F.Cu")
		(at 322.287138 -15.855188)
		(property "Reference" "R1747"
			(at 0 0 0)
			(layer "F.SilkS")
			(hide yes)
			(effects
				(font
					(size 1.27 1.27)
				)
			)
		)
		(property "Value" ""
			(at 0 0 0)
			(layer "F.Fab")
			(effects
				(font
					(size 1.27 1.27)
				)
			)
		)
		(duplicate_pad_numbers_are_jumpers no)
		(fp_line
			(start -1.651 -0.8382)
			(end 1.651 -0.8382)
			(stroke
				(width 0.1524)
				(type default)
			)
			(layer "F.SilkS")
		)
		(fp_line
			(start -1.651 0.8382)
			(end -1.651 -0.8382)
			(stroke
				(width 0.1524)
				(type default)
			)
			(layer "F.SilkS")
		)
		(fp_line
			(start 1.651 -0.8382)
			(end 1.651 0.8382)
			(stroke
				(width 0.1524)
				(type default)
			)
			(layer "F.SilkS")
		)
		(fp_line
			(start 1.651 0.8382)
			(end -1.651 0.8382)
			(stroke
				(width 0.1524)
				(type default)
			)
			(layer "F.SilkS")
		)
		(fp_line
			(start -1.559814 -0.7366)
			(end -1.559814 0.7366)
			(stroke
				(width 0.1)
				(type default)
			)
			(layer "F.Fab")
		)
		(fp_line
			(start -1.559814 0.7366)
			(end -1.524 0.7366)
			(stroke
				(width 0.1)
				(type default)
			)
			(layer "F.Fab")
		)
		(fp_line
			(start -1.524 -0.7366)
			(end -1.559814 -0.7366)
			(stroke
				(width 0.1)
				(type default)
			)
			(layer "F.Fab")
		)
		(fp_line
			(start -1.524 0.7366)
			(end 1.524 0.7366)
			(stroke
				(width 0.1)
				(type default)
			)
			(layer "F.Fab")
		)
		(fp_line
			(start 1.524 -0.7366)
			(end -1.524 -0.7366)
			(stroke
				(width 0.1)
				(type default)
			)
			(layer "F.Fab")
		)
		(fp_line
			(start 1.524 0.7366)
			(end 1.560576 0.7366)
			(stroke
				(width 0.1)
				(type default)
			)
			(layer "F.Fab")
		)
		(fp_line
			(start 1.560576 -0.7366)
			(end 1.524 -0.7366)
			(stroke
				(width 0.1)
				(type default)
			)
			(layer "F.Fab")
		)
		(fp_line
			(start 1.560576 0.7366)
			(end 1.560576 -0.7366)
			(stroke
				(width 0.1)
				(type default)
			)
			(layer "F.Fab")
		)
		(pad "1" smd rect
			(at -0.94996 0 180)
			(size 1.1176 1.3716)
			(layers "F.Cu" "F.Mask" "F.Paste")
			(net "P1V8_PCH_AUX")
		)
		(pad "2" smd rect
			(at 0.94996 0 180)
			(size 1.1176 1.3716)
			(layers "F.Cu" "F.Mask" "F.Paste")
			(net "PGPPA_AUX")
		)
	)
)
